FILE_TYPE = CONNECTIVITY;
{Allegro Design Entry HDL 16.5-S008 (v16-5-13Y) 10/18/2011}
"PAGE_NUMBER" = 1;
0"NC";
1"G\I";
2"P3V3 \G";
%"SYNONYM"
"1","(1850,2050)","0","mstr_standard","4P";
;
NEEDS_NO_SIZE"TRUE"
BODY_TYPE"PLUMBING"
CDS_LIB"mstr_standard";
"A\NWC\NAC"1;
"A\NWC\NAC"2;
%"DRAWING"
"2","(1275,1750)","0","mstr_standard","";
;
LAST_MODIFIED"Tue Oct 25 14:25:02 2011"
TITLE"P3V3"
ABBREV"P3V3";
END.
